(kicad_pcb
	(version 20260206)
	(generator "pcbnew")
	(generator_version "10.0")
	(general
		(thickness 1.6)
		(legacy_teardrops no)
	)
	(paper "A4")
	(title_block
		(title "04192023_DAF0TMB3IC0_F0TG_MB_C_brd_V02_OCP.brd")
		(comment 1 "Grand Teton / footprints 5175-5180 of 8354")
	)
	(layers
		(0 "F.Cu" signal "TOP")
		(4 "In1.Cu" signal "GND")
		(6 "In2.Cu" signal "IN1")
		(8 "In3.Cu" signal "GND1")
		(10 "In4.Cu" signal "IN2")
		(12 "In5.Cu" signal "GND2")
		(14 "In6.Cu" signal "IN3")
		(16 "In7.Cu" signal "GND3")
		(18 "In8.Cu" signal "VCC")
		(20 "In9.Cu" signal "VCC1")
		(22 "In10.Cu" signal "GND4")
		(24 "In11.Cu" signal "IN4")
		(26 "In12.Cu" signal "GND5")
		(28 "In13.Cu" signal "IN5")
		(30 "In14.Cu" signal "GND6")
		(32 "In15.Cu" signal "IN6")
		(34 "In16.Cu" signal "GND7")
		(2 "B.Cu" signal "BOTTOM")
		(9 "F.Adhes" user "F.Adhesive")
		(11 "B.Adhes" user "B.Adhesive")
		(13 "F.Paste" user "Package Geometry/Pastemask Top")
		(15 "B.Paste" user "Package Geometry/Pastemask Bottom")
		(5 "F.SilkS" user "Ref Des/Silkscreen Top")
		(7 "B.SilkS" user "Ref Des/Silkscreen Bottom")
		(1 "F.Mask" user "Board Geometry/Soldermask Top")
		(3 "B.Mask" user "Board Geometry/Soldermask Bottom")
		(17 "Dwgs.User" user "User.Drawings")
		(19 "Cmts.User" user "User.Comments")
		(21 "Eco1.User" user "User.Eco1")
		(23 "Eco2.User" user "User.Eco2")
		(25 "Edge.Cuts" user "Board Geometry/Outline")
		(27 "Margin" user)
		(31 "F.CrtYd" user "Package Geometry/Place Bound Top")
		(29 "B.CrtYd" user "Package Geometry/Place Bound Bottom")
		(35 "F.Fab" user "Ref Des/Assembly Top")
		(33 "B.Fab" user "Ref Des/Assembly Bottom")
	)
	(footprint ""
		(layer "B.Cu")
		(at 320.272664 -73.534778)
		(property "Reference" "Q78"
			(at 1.4224 -1.768348 0)
			(unlocked yes)
			(layer "B.SilkS")
			(effects
				(font
					(size 0.7874 0.5842)
					(thickness 0.1524)
				)
				(justify left mirror)
			)
		)
		(property "Value" ""
			(at 0 0 0)
			(layer "B.Fab")
			(effects
				(font
					(size 1.27 1.27)
				)
				(justify mirror)
			)
		)
		(duplicate_pad_numbers_are_jumpers no)
		(fp_line
			(start -1.332738 -1.100074)
			(end -1.332738 1.100074)
			(stroke
				(width 0.1524)
				(type default)
			)
			(layer "B.SilkS")
		)
		(fp_line
			(start -1.332738 1.100074)
			(end 1.332738 1.100074)
			(stroke
				(width 0.1524)
				(type default)
			)
			(layer "B.SilkS")
		)
		(fp_line
			(start -0.4826 -1.100074)
			(end -1.332738 -1.100074)
			(stroke
				(width 0.1524)
				(type default)
			)
			(layer "B.SilkS")
		)
		(fp_line
			(start 0 -0.541274)
			(end -0.4826 -1.100074)
			(stroke
				(width 0.1524)
				(type default)
			)
			(layer "B.SilkS")
		)
		(fp_line
			(start 0.4826 -1.100074)
			(end 0 -0.541274)
			(stroke
				(width 0.1524)
				(type default)
			)
			(layer "B.SilkS")
		)
		(fp_line
			(start 1.332738 -1.100074)
			(end 0.4826 -1.100074)
			(stroke
				(width 0.1524)
				(type default)
			)
			(layer "B.SilkS")
		)
		(fp_line
			(start 1.332738 1.100074)
			(end 1.332738 -1.100074)
			(stroke
				(width 0.1524)
				(type default)
			)
			(layer "B.SilkS")
		)
		(fp_poly
			(pts
				(xy 1.489456 -1.189482) (xy 1.737614 -1.933956) (xy 2.23393 -1.43764)
			)
			(stroke
				(width 0)
				(type default)
			)
			(fill yes)
			(layer "B.SilkS")
		)
		(fp_line
			(start -0.674878 -1.100074)
			(end -0.674878 1.100074)
			(stroke
				(width 0.1)
				(type default)
			)
			(layer "B.Fab")
		)
		(fp_line
			(start -0.674878 1.100074)
			(end 0.674878 1.100074)
			(stroke
				(width 0.1)
				(type default)
			)
			(layer "B.Fab")
		)
		(fp_line
			(start 0.674878 -1.100074)
			(end -0.674878 -1.100074)
			(stroke
				(width 0.1)
				(type default)
			)
			(layer "B.Fab")
		)
		(fp_line
			(start 0.674878 1.100074)
			(end 0.674878 -1.100074)
			(stroke
				(width 0.1)
				(type default)
			)
			(layer "B.Fab")
		)
		(fp_poly
			(pts
				(xy 2.2352 -0.298958) (xy 2.2352 -1.001014) (xy 1.533144 -0.649986)
			)
			(stroke
				(width 0)
				(type default)
			)
			(fill yes)
			(layer "B.Fab")
		)
		(pad "1" smd rect
			(at 0.94996 -0.649986 90)
			(size 0.4318 0.508)
			(layers "B.Cu" "B.Mask" "B.Paste")
			(net "GND")
		)
		(pad "2" smd rect
			(at 0.94996 0 90)
			(size 0.4318 0.508)
			(layers "B.Cu" "B.Mask" "B.Paste")
			(net "PWRGD_P1V8_AUX_R")
		)
		(pad "3" smd rect
			(at 0.94996 0.649986 90)
			(size 0.4318 0.508)
			(layers "B.Cu" "B.Mask" "B.Paste")
			(net "LED_PWRGD_PS_PWROK_PLD_D")
		)
		(pad "4" smd rect
			(at -0.94996 0.649986 90)
			(size 0.4318 0.508)
			(layers "B.Cu" "B.Mask" "B.Paste")
			(net "GND")
		)
		(pad "5" smd rect
			(at -0.94996 0 90)
			(size 0.4318 0.508)
			(layers "B.Cu" "B.Mask" "B.Paste")
			(net "PWRGD_PS_PWROK_PLD")
		)
		(pad "6" smd rect
			(at -0.94996 -0.649986 90)
			(size 0.4318 0.508)
			(layers "B.Cu" "B.Mask" "B.Paste")
			(net "LED_PWRGD_P1V8_AUX_D")
		)
	)
	(footprint ""
		(layer "B.Cu")
		(at 324.635876 -66.708782 90)
		(property "Reference" "R3087"
			(at 0 0 90)
			(layer "B.SilkS")
			(hide yes)
			(effects
				(font
					(size 1.27 1.27)
				)
				(justify mirror)
			)
		)
		(property "Value" ""
			(at 0 0 90)
			(layer "B.Fab")
			(effects
				(font
					(size 1.27 1.27)
				)
				(justify mirror)
			)
		)
		(duplicate_pad_numbers_are_jumpers no)
		(fp_line
			(start 0.7874 -0.4064)
			(end -0.7874 -0.4064)
			(stroke
				(width 0.1524)
				(type default)
			)
			(layer "B.SilkS")
		)
		(fp_line
			(start -0.7874 -0.4064)
			(end -0.7874 0.4064)
			(stroke
				(width 0.1524)
				(type default)
			)
			(layer "B.SilkS")
		)
		(fp_line
			(start 0.7874 0.4064)
			(end 0.7874 -0.4064)
			(stroke
				(width 0.1524)
				(type default)
			)
			(layer "B.SilkS")
		)
		(fp_line
			(start -0.7874 0.4064)
			(end 0.7874 0.4064)
			(stroke
				(width 0.1524)
				(type default)
			)
			(layer "B.SilkS")
		)
		(fp_line
			(start 0.67945 -0.305054)
			(end 0.12065 -0.305054)
			(stroke
				(width 0.1)
				(type default)
			)
			(layer "B.Fab")
		)
		(fp_line
			(start 0.12065 -0.305054)
			(end 0.12065 -0.2794)
			(stroke
				(width 0.1)
				(type default)
			)
			(layer "B.Fab")
		)
		(fp_line
			(start -0.12065 -0.3048)
			(end -0.67945 -0.3048)
			(stroke
				(width 0.1)
				(type default)
			)
			(layer "B.Fab")
		)
		(fp_line
			(start -0.67945 -0.3048)
			(end -0.67945 0.3048)
			(stroke
				(width 0.1)
				(type default)
			)
			(layer "B.Fab")
		)
		(fp_line
			(start 0.12065 -0.2794)
			(end -0.12065 -0.2794)
			(stroke
				(width 0.1)
				(type default)
			)
			(layer "B.Fab")
		)
		(fp_line
			(start -0.12065 -0.2794)
			(end -0.12065 -0.3048)
			(stroke
				(width 0.1)
				(type default)
			)
			(layer "B.Fab")
		)
		(fp_line
			(start 0.12065 0.2794)
			(end 0.12065 0.3048)
			(stroke
				(width 0.1)
				(type default)
			)
			(layer "B.Fab")
		)
		(fp_line
			(start -0.120396 0.2794)
			(end 0.12065 0.2794)
			(stroke
				(width 0.1)
				(type default)
			)
			(layer "B.Fab")
		)
		(fp_line
			(start 0.67945 0.3048)
			(end 0.67945 -0.305054)
			(stroke
				(width 0.1)
				(type default)
			)
			(layer "B.Fab")
		)
		(fp_line
			(start 0.12065 0.3048)
			(end 0.67945 0.3048)
			(stroke
				(width 0.1)
				(type default)
			)
			(layer "B.Fab")
		)
		(fp_line
			(start -0.120396 0.3048)
			(end -0.120396 0.2794)
			(stroke
				(width 0.1)
				(type default)
			)
			(layer "B.Fab")
		)
		(fp_line
			(start -0.67945 0.3048)
			(end -0.120396 0.3048)
			(stroke
				(width 0.1)
				(type default)
			)
			(layer "B.Fab")
		)
		(pad "1" smd circle
			(at 0.40005 0 270)
			(size 0 0)
			(layers "B.Cu" "B.Mask" "B.Paste")
			(net "LED_PWRGD_PVDDCR_CPU0_P0_R")
		)
		(pad "2" smd circle
			(at -0.40005 0 270)
			(size 0 0)
			(layers "B.Cu" "B.Mask" "B.Paste")
			(net "P3V3_AUX")
		)
	)
	(footprint ""
		(layer "B.Cu")
		(at 20.919186 -193.996564)
		(property "Reference" "C156"
			(at 0 0 0)
			(layer "B.SilkS")
			(hide yes)
			(effects
				(font
					(size 1.27 1.27)
				)
				(justify mirror)
			)
		)
		(property "Value" ""
			(at 0 0 0)
			(layer "B.Fab")
			(effects
				(font
					(size 1.27 1.27)
				)
				(justify mirror)
			)
		)
		(duplicate_pad_numbers_are_jumpers no)
		(fp_line
			(start -0.7874 -0.4064)
			(end -0.7874 0.4064)
			(stroke
				(width 0.1524)
				(type default)
			)
			(layer "B.SilkS")
		)
		(fp_line
			(start -0.7874 0.4064)
			(end 0.7874 0.4064)
			(stroke
				(width 0.1524)
				(type default)
			)
			(layer "B.SilkS")
		)
		(fp_line
			(start 0.7874 -0.4064)
			(end -0.7874 -0.4064)
			(stroke
				(width 0.1524)
				(type default)
			)
			(layer "B.SilkS")
		)
		(fp_line
			(start 0.7874 0.4064)
			(end 0.7874 -0.4064)
			(stroke
				(width 0.1524)
				(type default)
			)
			(layer "B.SilkS")
		)
		(fp_line
			(start -0.67945 -0.3048)
			(end -0.67945 0.3048)
			(stroke
				(width 0.1)
				(type default)
			)
			(layer "B.Fab")
		)
		(fp_line
			(start -0.67945 0.3048)
			(end -0.120396 0.3048)
			(stroke
				(width 0.1)
				(type default)
			)
			(layer "B.Fab")
		)
		(fp_line
			(start -0.12065 -0.3048)
			(end -0.67945 -0.3048)
			(stroke
				(width 0.1)
				(type default)
			)
			(layer "B.Fab")
		)
		(fp_line
			(start -0.12065 -0.2794)
			(end -0.12065 -0.3048)
			(stroke
				(width 0.1)
				(type default)
			)
			(layer "B.Fab")
		)
		(fp_line
			(start -0.120396 0.2794)
			(end 0.12065 0.2794)
			(stroke
				(width 0.1)
				(type default)
			)
			(layer "B.Fab")
		)
		(fp_line
			(start -0.120396 0.3048)
			(end -0.120396 0.2794)
			(stroke
				(width 0.1)
				(type default)
			)
			(layer "B.Fab")
		)
		(fp_line
			(start 0.12065 -0.305054)
			(end 0.12065 -0.2794)
			(stroke
				(width 0.1)
				(type default)
			)
			(layer "B.Fab")
		)
		(fp_line
			(start 0.12065 -0.2794)
			(end -0.12065 -0.2794)
			(stroke
				(width 0.1)
				(type default)
			)
			(layer "B.Fab")
		)
		(fp_line
			(start 0.12065 0.2794)
			(end 0.12065 0.3048)
			(stroke
				(width 0.1)
				(type default)
			)
			(layer "B.Fab")
		)
		(fp_line
			(start 0.12065 0.3048)
			(end 0.67945 0.3048)
			(stroke
				(width 0.1)
				(type default)
			)
			(layer "B.Fab")
		)
		(fp_line
			(start 0.67945 -0.305054)
			(end 0.12065 -0.305054)
			(stroke
				(width 0.1)
				(type default)
			)
			(layer "B.Fab")
		)
		(fp_line
			(start 0.67945 0.3048)
			(end 0.67945 -0.305054)
			(stroke
				(width 0.1)
				(type default)
			)
			(layer "B.Fab")
		)
		(pad "1" smd circle
			(at 0.40005 0 180)
			(size 0 0)
			(layers "B.Cu" "B.Mask" "B.Paste")
			(net "P3V3_AUX")
		)
		(pad "2" smd circle
			(at -0.40005 0 180)
			(size 0 0)
			(layers "B.Cu" "B.Mask" "B.Paste")
			(net "GND")
		)
	)
	(footprint ""
		(layer "B.Cu")
		(at 164.508688 -9.013444 90)
		(property "Reference" "R55"
			(at 0 0 90)
			(layer "B.SilkS")
			(hide yes)
			(effects
				(font
					(size 1.27 1.27)
				)
				(justify mirror)
			)
		)
		(property "Value" ""
			(at 0 0 90)
			(layer "B.Fab")
			(effects
				(font
					(size 1.27 1.27)
				)
				(justify mirror)
			)
		)
		(duplicate_pad_numbers_are_jumpers no)
		(fp_line
			(start 0.7874 -0.4064)
			(end -0.7874 -0.4064)
			(stroke
				(width 0.1524)
				(type default)
			)
			(layer "B.SilkS")
		)
		(fp_line
			(start -0.7874 -0.4064)
			(end -0.7874 0.4064)
			(stroke
				(width 0.1524)
				(type default)
			)
			(layer "B.SilkS")
		)
		(fp_line
			(start 0.7874 0.4064)
			(end 0.7874 -0.4064)
			(stroke
				(width 0.1524)
				(type default)
			)
			(layer "B.SilkS")
		)
		(fp_line
			(start -0.7874 0.4064)
			(end 0.7874 0.4064)
			(stroke
				(width 0.1524)
				(type default)
			)
			(layer "B.SilkS")
		)
		(fp_line
			(start 0.67945 -0.305054)
			(end 0.12065 -0.305054)
			(stroke
				(width 0.1)
				(type default)
			)
			(layer "B.Fab")
		)
		(fp_line
			(start 0.12065 -0.305054)
			(end 0.12065 -0.2794)
			(stroke
				(width 0.1)
				(type default)
			)
			(layer "B.Fab")
		)
		(fp_line
			(start -0.12065 -0.3048)
			(end -0.67945 -0.3048)
			(stroke
				(width 0.1)
				(type default)
			)
			(layer "B.Fab")
		)
		(fp_line
			(start -0.67945 -0.3048)
			(end -0.67945 0.3048)
			(stroke
				(width 0.1)
				(type default)
			)
			(layer "B.Fab")
		)
		(fp_line
			(start 0.12065 -0.2794)
			(end -0.12065 -0.2794)
			(stroke
				(width 0.1)
				(type default)
			)
			(layer "B.Fab")
		)
		(fp_line
			(start -0.12065 -0.2794)
			(end -0.12065 -0.3048)
			(stroke
				(width 0.1)
				(type default)
			)
			(layer "B.Fab")
		)
		(fp_line
			(start 0.12065 0.2794)
			(end 0.12065 0.3048)
			(stroke
				(width 0.1)
				(type default)
			)
			(layer "B.Fab")
		)
		(fp_line
			(start -0.120396 0.2794)
			(end 0.12065 0.2794)
			(stroke
				(width 0.1)
				(type default)
			)
			(layer "B.Fab")
		)
		(fp_line
			(start 0.67945 0.3048)
			(end 0.67945 -0.305054)
			(stroke
				(width 0.1)
				(type default)
			)
			(layer "B.Fab")
		)
		(fp_line
			(start 0.12065 0.3048)
			(end 0.67945 0.3048)
			(stroke
				(width 0.1)
				(type default)
			)
			(layer "B.Fab")
		)
		(fp_line
			(start -0.120396 0.3048)
			(end -0.120396 0.2794)
			(stroke
				(width 0.1)
				(type default)
			)
			(layer "B.Fab")
		)
		(fp_line
			(start -0.67945 0.3048)
			(end -0.120396 0.3048)
			(stroke
				(width 0.1)
				(type default)
			)
			(layer "B.Fab")
		)
		(pad "1" smd circle
			(at 0.40005 0 270)
			(size 0 0)
			(layers "B.Cu" "B.Mask" "B.Paste")
			(net "SMB_PCIE0_3V3AUX_SDA")
		)
		(pad "2" smd circle
			(at -0.40005 0 270)
			(size 0 0)
			(layers "B.Cu" "B.Mask" "B.Paste")
			(net "SMB_PCIE0_3V3AUX_SDA_R")
		)
	)
	(footprint ""
		(layer "B.Cu")
		(at 153.865834 -322.903342 -90)
		(property "Reference" "R754"
			(at 0 0 90)
			(layer "B.SilkS")
			(hide yes)
			(effects
				(font
					(size 1.27 1.27)
				)
				(justify mirror)
			)
		)
		(property "Value" ""
			(at 0 0 90)
			(layer "B.Fab")
			(effects
				(font
					(size 1.27 1.27)
				)
				(justify mirror)
			)
		)
		(duplicate_pad_numbers_are_jumpers no)
		(fp_line
			(start -0.7874 0.4064)
			(end 0.7874 0.4064)
			(stroke
				(width 0.1524)
				(type default)
			)
			(layer "B.SilkS")
		)
		(fp_line
			(start 0.7874 0.4064)
			(end 0.7874 -0.4064)
			(stroke
				(width 0.1524)
				(type default)
			)
			(layer "B.SilkS")
		)
		(fp_line
			(start -0.7874 -0.4064)
			(end -0.7874 0.4064)
			(stroke
				(width 0.1524)
				(type default)
			)
			(layer "B.SilkS")
		)
		(fp_line
			(start 0.7874 -0.4064)
			(end -0.7874 -0.4064)
			(stroke
				(width 0.1524)
				(type default)
			)
			(layer "B.SilkS")
		)
		(fp_line
			(start -0.67945 0.3048)
			(end -0.120396 0.3048)
			(stroke
				(width 0.1)
				(type default)
			)
			(layer "B.Fab")
		)
		(fp_line
			(start -0.120396 0.3048)
			(end -0.120396 0.2794)
			(stroke
				(width 0.1)
				(type default)
			)
			(layer "B.Fab")
		)
		(fp_line
			(start 0.12065 0.3048)
			(end 0.67945 0.3048)
			(stroke
				(width 0.1)
				(type default)
			)
			(layer "B.Fab")
		)
		(fp_line
			(start 0.67945 0.3048)
			(end 0.67945 -0.305054)
			(stroke
				(width 0.1)
				(type default)
			)
			(layer "B.Fab")
		)
		(fp_line
			(start -0.120396 0.2794)
			(end 0.12065 0.2794)
			(stroke
				(width 0.1)
				(type default)
			)
			(layer "B.Fab")
		)
		(fp_line
			(start 0.12065 0.2794)
			(end 0.12065 0.3048)
			(stroke
				(width 0.1)
				(type default)
			)
			(layer "B.Fab")
		)
		(fp_line
			(start -0.12065 -0.2794)
			(end -0.12065 -0.3048)
			(stroke
				(width 0.1)
				(type default)
			)
			(layer "B.Fab")
		)
		(fp_line
			(start 0.12065 -0.2794)
			(end -0.12065 -0.2794)
			(stroke
				(width 0.1)
				(type default)
			)
			(layer "B.Fab")
		)
		(fp_line
			(start -0.67945 -0.3048)
			(end -0.67945 0.3048)
			(stroke
				(width 0.1)
				(type default)
			)
			(layer "B.Fab")
		)
		(fp_line
			(start -0.12065 -0.3048)
			(end -0.67945 -0.3048)
			(stroke
				(width 0.1)
				(type default)
			)
			(layer "B.Fab")
		)
		(fp_line
			(start 0.12065 -0.305054)
			(end 0.12065 -0.2794)
			(stroke
				(width 0.1)
				(type default)
			)
			(layer "B.Fab")
		)
		(fp_line
			(start 0.67945 -0.305054)
			(end 0.12065 -0.305054)
			(stroke
				(width 0.1)
				(type default)
			)
			(layer "B.Fab")
		)
		(pad "1" smd circle
			(at 0.40005 0 90)
			(size 0 0)
			(layers "B.Cu" "B.Mask" "B.Paste")
			(net "GND")
		)
		(pad "2" smd circle
			(at -0.40005 0 90)
			(size 0 0)
			(layers "B.Cu" "B.Mask" "B.Paste")
			(net "SPI_CPU1_CLK")
		)
	)
	(footprint ""
		(layer "B.Cu")
		(at 98.918522 -150.698962 -90)
		(property "Reference" "PR437"
			(at 0 0 90)
			(layer "B.SilkS")
			(hide yes)
			(effects
				(font
					(size 1.27 1.27)
				)
				(justify mirror)
			)
		)
		(property "Value" ""
			(at 0 0 90)
			(layer "B.Fab")
			(effects
				(font
					(size 1.27 1.27)
				)
				(justify mirror)
			)
		)
		(duplicate_pad_numbers_are_jumpers no)
		(fp_line
			(start -0.7874 0.4064)
			(end 0.7874 0.4064)
			(stroke
				(width 0.1524)
				(type default)
			)
			(layer "B.SilkS")
		)
		(fp_line
			(start 0.7874 0.4064)
			(end 0.7874 -0.4064)
			(stroke
				(width 0.1524)
				(type default)
			)
			(layer "B.SilkS")
		)
		(fp_line
			(start -0.7874 -0.4064)
			(end -0.7874 0.4064)
			(stroke
				(width 0.1524)
				(type default)
			)
			(layer "B.SilkS")
		)
		(fp_line
			(start 0.7874 -0.4064)
			(end -0.7874 -0.4064)
			(stroke
				(width 0.1524)
				(type default)
			)
			(layer "B.SilkS")
		)
		(fp_line
			(start -0.67945 0.3048)
			(end -0.120396 0.3048)
			(stroke
				(width 0.1)
				(type default)
			)
			(layer "B.Fab")
		)
		(fp_line
			(start -0.120396 0.3048)
			(end -0.120396 0.2794)
			(stroke
				(width 0.1)
				(type default)
			)
			(layer "B.Fab")
		)
		(fp_line
			(start 0.12065 0.3048)
			(end 0.67945 0.3048)
			(stroke
				(width 0.1)
				(type default)
			)
			(layer "B.Fab")
		)
		(fp_line
			(start 0.67945 0.3048)
			(end 0.67945 -0.305054)
			(stroke
				(width 0.1)
				(type default)
			)
			(layer "B.Fab")
		)
		(fp_line
			(start -0.120396 0.2794)
			(end 0.12065 0.2794)
			(stroke
				(width 0.1)
				(type default)
			)
			(layer "B.Fab")
		)
		(fp_line
			(start 0.12065 0.2794)
			(end 0.12065 0.3048)
			(stroke
				(width 0.1)
				(type default)
			)
			(layer "B.Fab")
		)
		(fp_line
			(start -0.12065 -0.2794)
			(end -0.12065 -0.3048)
			(stroke
				(width 0.1)
				(type default)
			)
			(layer "B.Fab")
		)
		(fp_line
			(start 0.12065 -0.2794)
			(end -0.12065 -0.2794)
			(stroke
				(width 0.1)
				(type default)
			)
			(layer "B.Fab")
		)
		(fp_line
			(start -0.67945 -0.3048)
			(end -0.67945 0.3048)
			(stroke
				(width 0.1)
				(type default)
			)
			(layer "B.Fab")
		)
		(fp_line
			(start -0.12065 -0.3048)
			(end -0.67945 -0.3048)
			(stroke
				(width 0.1)
				(type default)
			)
			(layer "B.Fab")
		)
		(fp_line
			(start 0.12065 -0.305054)
			(end 0.12065 -0.2794)
			(stroke
				(width 0.1)
				(type default)
			)
			(layer "B.Fab")
		)
		(fp_line
			(start 0.67945 -0.305054)
			(end 0.12065 -0.305054)
			(stroke
				(width 0.1)
				(type default)
			)
			(layer "B.Fab")
		)
		(pad "1" smd circle
			(at 0.40005 0 90)
			(size 0 0)
			(layers "B.Cu" "B.Mask" "B.Paste")
			(net "NC_PVDDCR_CPU0_P1_IMON9")
		)
		(pad "2" smd circle
			(at -0.40005 0 90)
			(size 0 0)
			(layers "B.Cu" "B.Mask" "B.Paste")
			(net "GND")
		)
	)
)
